(kicad_pcb
	(version 20260206)
	(generator "pcbnew")
	(generator_version "10.0")
	(general
		(thickness 1.6)
		(legacy_teardrops no)
	)
	(paper "A4")
	(title_block
		(title "01162023_DA0F0TEBIF0_F0T_Expander_BD_F_brd_V02_OCP.brd")
		(comment 1 "Grand Teton / footprints 3891-3895 of 9728")
	)
	(layers
		(0 "F.Cu" signal "TOP")
		(4 "In1.Cu" signal "GND")
		(6 "In2.Cu" signal "VCC")
		(8 "In3.Cu" signal "VCC1")
		(10 "In4.Cu" signal "GND1")
		(12 "In5.Cu" signal "IN1")
		(14 "In6.Cu" signal "GND2")
		(16 "In7.Cu" signal "IN2")
		(18 "In8.Cu" signal "GND3")
		(20 "In9.Cu" signal "IN3")
		(22 "In10.Cu" signal "GND4")
		(24 "In11.Cu" signal "IN4")
		(26 "In12.Cu" signal "GND5")
		(28 "In13.Cu" signal "IN5")
		(30 "In14.Cu" signal "GND6")
		(32 "In15.Cu" signal "IN6")
		(34 "In16.Cu" signal "GND7")
		(2 "B.Cu" signal "BOTTOM")
		(9 "F.Adhes" user "F.Adhesive")
		(11 "B.Adhes" user "B.Adhesive")
		(13 "F.Paste" user "Package Geometry/Pastemask Top")
		(15 "B.Paste" user "Package Geometry/Pastemask Bottom")
		(5 "F.SilkS" user "Ref Des/Silkscreen Top")
		(7 "B.SilkS" user "Ref Des/Silkscreen Bottom")
		(1 "F.Mask" user "Board Geometry/Soldermask Top")
		(3 "B.Mask" user "Board Geometry/Soldermask Bottom")
		(17 "Dwgs.User" user "User.Drawings")
		(19 "Cmts.User" user "User.Comments")
		(21 "Eco1.User" user "User.Eco1")
		(23 "Eco2.User" user "User.Eco2")
		(25 "Edge.Cuts" user "Board Geometry/Outline")
		(27 "Margin" user)
		(31 "F.CrtYd" user "Package Geometry/Place Bound Top")
		(29 "B.CrtYd" user "Package Geometry/Place Bound Bottom")
		(35 "F.Fab" user "Ref Des/Assembly Top")
		(33 "B.Fab" user "Ref Des/Assembly Bottom")
	)
	(footprint ""
		(layer "F.Cu")
		(at 323.23405 -306.074572 90)
		(property "Reference" "R1373"
			(at 0 0 90)
			(layer "F.SilkS")
			(hide yes)
			(effects
				(font
					(size 1.27 1.27)
				)
			)
		)
		(property "Value" ""
			(at 0 0 90)
			(layer "F.Fab")
			(effects
				(font
					(size 1.27 1.27)
				)
			)
		)
		(duplicate_pad_numbers_are_jumpers no)
		(fp_line
			(start 0.7874 -0.4064)
			(end 0.7874 0.4064)
			(stroke
				(width 0.1524)
				(type default)
			)
			(layer "F.SilkS")
		)
		(fp_line
			(start -0.7874 -0.4064)
			(end 0.7874 -0.4064)
			(stroke
				(width 0.1524)
				(type default)
			)
			(layer "F.SilkS")
		)
		(fp_line
			(start 0.7874 0.4064)
			(end -0.7874 0.4064)
			(stroke
				(width 0.1524)
				(type default)
			)
			(layer "F.SilkS")
		)
		(fp_line
			(start -0.7874 0.4064)
			(end -0.7874 -0.4064)
			(stroke
				(width 0.1524)
				(type default)
			)
			(layer "F.SilkS")
		)
		(fp_line
			(start -0.12065 -0.305054)
			(end -0.12065 -0.2794)
			(stroke
				(width 0.1)
				(type default)
			)
			(layer "F.Fab")
		)
		(fp_line
			(start -0.67945 -0.305054)
			(end -0.12065 -0.305054)
			(stroke
				(width 0.1)
				(type default)
			)
			(layer "F.Fab")
		)
		(fp_line
			(start 0.67945 -0.3048)
			(end 0.67945 0.3048)
			(stroke
				(width 0.1)
				(type default)
			)
			(layer "F.Fab")
		)
		(fp_line
			(start 0.12065 -0.3048)
			(end 0.67945 -0.3048)
			(stroke
				(width 0.1)
				(type default)
			)
			(layer "F.Fab")
		)
		(fp_line
			(start 0.12065 -0.2794)
			(end 0.12065 -0.3048)
			(stroke
				(width 0.1)
				(type default)
			)
			(layer "F.Fab")
		)
		(fp_line
			(start -0.12065 -0.2794)
			(end 0.12065 -0.2794)
			(stroke
				(width 0.1)
				(type default)
			)
			(layer "F.Fab")
		)
		(fp_line
			(start 0.120396 0.2794)
			(end -0.12065 0.2794)
			(stroke
				(width 0.1)
				(type default)
			)
			(layer "F.Fab")
		)
		(fp_line
			(start -0.12065 0.2794)
			(end -0.12065 0.3048)
			(stroke
				(width 0.1)
				(type default)
			)
			(layer "F.Fab")
		)
		(fp_line
			(start 0.67945 0.3048)
			(end 0.120396 0.3048)
			(stroke
				(width 0.1)
				(type default)
			)
			(layer "F.Fab")
		)
		(fp_line
			(start 0.120396 0.3048)
			(end 0.120396 0.2794)
			(stroke
				(width 0.1)
				(type default)
			)
			(layer "F.Fab")
		)
		(fp_line
			(start -0.12065 0.3048)
			(end -0.67945 0.3048)
			(stroke
				(width 0.1)
				(type default)
			)
			(layer "F.Fab")
		)
		(fp_line
			(start -0.67945 0.3048)
			(end -0.67945 -0.305054)
			(stroke
				(width 0.1)
				(type default)
			)
			(layer "F.Fab")
		)
		(pad "1" smd circle
			(at -0.40005 0 90)
			(size 0 0)
			(layers "F.Cu" "F.Mask" "F.Paste")
			(net "PEX2_SPARE1")
		)
		(pad "2" smd circle
			(at 0.40005 0 90)
			(size 0 0)
			(layers "F.Cu" "F.Mask" "F.Paste")
			(net "P1V8_PEX")
		)
	)
	(footprint ""
		(layer "F.Cu")
		(at 363.793532 -357.96601 90)
		(property "Reference" "C4164"
			(at 0 0 90)
			(layer "F.SilkS")
			(hide yes)
			(effects
				(font
					(size 1.27 1.27)
				)
			)
		)
		(property "Value" ""
			(at 0 0 90)
			(layer "F.Fab")
			(effects
				(font
					(size 1.27 1.27)
				)
			)
		)
		(duplicate_pad_numbers_are_jumpers no)
		(fp_line
			(start 0.7874 -0.4064)
			(end 0.7874 0.4064)
			(stroke
				(width 0.1524)
				(type default)
			)
			(layer "F.SilkS")
		)
		(fp_line
			(start -0.7874 -0.4064)
			(end 0.7874 -0.4064)
			(stroke
				(width 0.1524)
				(type default)
			)
			(layer "F.SilkS")
		)
		(fp_line
			(start 0.7874 0.4064)
			(end -0.7874 0.4064)
			(stroke
				(width 0.1524)
				(type default)
			)
			(layer "F.SilkS")
		)
		(fp_line
			(start -0.7874 0.4064)
			(end -0.7874 -0.4064)
			(stroke
				(width 0.1524)
				(type default)
			)
			(layer "F.SilkS")
		)
		(fp_line
			(start -0.12065 -0.305054)
			(end -0.12065 -0.2794)
			(stroke
				(width 0.1)
				(type default)
			)
			(layer "F.Fab")
		)
		(fp_line
			(start -0.67945 -0.305054)
			(end -0.12065 -0.305054)
			(stroke
				(width 0.1)
				(type default)
			)
			(layer "F.Fab")
		)
		(fp_line
			(start 0.67945 -0.3048)
			(end 0.67945 0.3048)
			(stroke
				(width 0.1)
				(type default)
			)
			(layer "F.Fab")
		)
		(fp_line
			(start 0.12065 -0.3048)
			(end 0.67945 -0.3048)
			(stroke
				(width 0.1)
				(type default)
			)
			(layer "F.Fab")
		)
		(fp_line
			(start 0.12065 -0.2794)
			(end 0.12065 -0.3048)
			(stroke
				(width 0.1)
				(type default)
			)
			(layer "F.Fab")
		)
		(fp_line
			(start -0.12065 -0.2794)
			(end 0.12065 -0.2794)
			(stroke
				(width 0.1)
				(type default)
			)
			(layer "F.Fab")
		)
		(fp_line
			(start 0.120396 0.2794)
			(end -0.12065 0.2794)
			(stroke
				(width 0.1)
				(type default)
			)
			(layer "F.Fab")
		)
		(fp_line
			(start -0.12065 0.2794)
			(end -0.12065 0.3048)
			(stroke
				(width 0.1)
				(type default)
			)
			(layer "F.Fab")
		)
		(fp_line
			(start 0.67945 0.3048)
			(end 0.120396 0.3048)
			(stroke
				(width 0.1)
				(type default)
			)
			(layer "F.Fab")
		)
		(fp_line
			(start 0.120396 0.3048)
			(end 0.120396 0.2794)
			(stroke
				(width 0.1)
				(type default)
			)
			(layer "F.Fab")
		)
		(fp_line
			(start -0.12065 0.3048)
			(end -0.67945 0.3048)
			(stroke
				(width 0.1)
				(type default)
			)
			(layer "F.Fab")
		)
		(fp_line
			(start -0.67945 0.3048)
			(end -0.67945 -0.305054)
			(stroke
				(width 0.1)
				(type default)
			)
			(layer "F.Fab")
		)
		(pad "1" smd circle
			(at -0.40005 0 90)
			(size 0 0)
			(layers "F.Cu" "F.Mask" "F.Paste")
			(net "GND")
		)
		(pad "2" smd circle
			(at 0.40005 0 90)
			(size 0 0)
			(layers "F.Cu" "F.Mask" "F.Paste")
			(net "MB_SWB_PWR_EN")
		)
	)
	(footprint ""
		(layer "F.Cu")
		(at 3.856736 -37.795962 -90)
		(property "Reference" "PR6920"
			(at 0 0 270)
			(layer "F.SilkS")
			(hide yes)
			(effects
				(font
					(size 1.27 1.27)
				)
			)
		)
		(property "Value" ""
			(at 0 0 270)
			(layer "F.Fab")
			(effects
				(font
					(size 1.27 1.27)
				)
			)
		)
		(duplicate_pad_numbers_are_jumpers no)
		(fp_line
			(start -0.7874 0.4064)
			(end -0.7874 -0.4064)
			(stroke
				(width 0.1524)
				(type default)
			)
			(layer "F.SilkS")
		)
		(fp_line
			(start 0.7874 0.4064)
			(end -0.7874 0.4064)
			(stroke
				(width 0.1524)
				(type default)
			)
			(layer "F.SilkS")
		)
		(fp_line
			(start -0.7874 -0.4064)
			(end 0.7874 -0.4064)
			(stroke
				(width 0.1524)
				(type default)
			)
			(layer "F.SilkS")
		)
		(fp_line
			(start 0.7874 -0.4064)
			(end 0.7874 0.4064)
			(stroke
				(width 0.1524)
				(type default)
			)
			(layer "F.SilkS")
		)
		(fp_line
			(start -0.67945 0.3048)
			(end -0.67945 -0.305054)
			(stroke
				(width 0.1)
				(type default)
			)
			(layer "F.Fab")
		)
		(fp_line
			(start -0.12065 0.3048)
			(end -0.67945 0.3048)
			(stroke
				(width 0.1)
				(type default)
			)
			(layer "F.Fab")
		)
		(fp_line
			(start 0.120396 0.3048)
			(end 0.120396 0.2794)
			(stroke
				(width 0.1)
				(type default)
			)
			(layer "F.Fab")
		)
		(fp_line
			(start 0.67945 0.3048)
			(end 0.120396 0.3048)
			(stroke
				(width 0.1)
				(type default)
			)
			(layer "F.Fab")
		)
		(fp_line
			(start -0.12065 0.2794)
			(end -0.12065 0.3048)
			(stroke
				(width 0.1)
				(type default)
			)
			(layer "F.Fab")
		)
		(fp_line
			(start 0.120396 0.2794)
			(end -0.12065 0.2794)
			(stroke
				(width 0.1)
				(type default)
			)
			(layer "F.Fab")
		)
		(fp_line
			(start -0.12065 -0.2794)
			(end 0.12065 -0.2794)
			(stroke
				(width 0.1)
				(type default)
			)
			(layer "F.Fab")
		)
		(fp_line
			(start 0.12065 -0.2794)
			(end 0.12065 -0.3048)
			(stroke
				(width 0.1)
				(type default)
			)
			(layer "F.Fab")
		)
		(fp_line
			(start 0.12065 -0.3048)
			(end 0.67945 -0.3048)
			(stroke
				(width 0.1)
				(type default)
			)
			(layer "F.Fab")
		)
		(fp_line
			(start 0.67945 -0.3048)
			(end 0.67945 0.3048)
			(stroke
				(width 0.1)
				(type default)
			)
			(layer "F.Fab")
		)
		(fp_line
			(start -0.67945 -0.305054)
			(end -0.12065 -0.305054)
			(stroke
				(width 0.1)
				(type default)
			)
			(layer "F.Fab")
		)
		(fp_line
			(start -0.12065 -0.305054)
			(end -0.12065 -0.2794)
			(stroke
				(width 0.1)
				(type default)
			)
			(layer "F.Fab")
		)
		(pad "1" smd circle
			(at -0.40005 0 270)
			(size 0 0)
			(layers "F.Cu" "F.Mask" "F.Paste")
			(net "P3V3_SSD0_CO_ILIMIT")
		)
		(pad "2" smd circle
			(at 0.40005 0 270)
			(size 0 0)
			(layers "F.Cu" "F.Mask" "F.Paste")
			(net "GND")
		)
	)
	(footprint ""
		(layer "F.Cu")
		(at 214.757 -202.692)
		(property "Reference" "U120"
			(at 0.338328 -2.096008 0)
			(unlocked yes)
			(layer "F.SilkS")
			(effects
				(font
					(size 0.7874 0.5842)
					(thickness 0.1524)
				)
				(justify left)
			)
		)
		(property "Value" ""
			(at 0 0 0)
			(layer "F.Fab")
			(effects
				(font
					(size 1.27 1.27)
				)
			)
		)
		(duplicate_pad_numbers_are_jumpers no)
		(fp_line
			(start -1.3208 -1.525016)
			(end -0.508 -1.525016)
			(stroke
				(width 0.1524)
				(type default)
			)
			(layer "F.SilkS")
		)
		(fp_line
			(start -1.3208 1.525016)
			(end -1.3208 -1.525016)
			(stroke
				(width 0.1524)
				(type default)
			)
			(layer "F.SilkS")
		)
		(fp_line
			(start -0.508 -1.525016)
			(end 0 -0.999998)
			(stroke
				(width 0.1524)
				(type default)
			)
			(layer "F.SilkS")
		)
		(fp_line
			(start 0 -0.999998)
			(end 0.508 -1.525016)
			(stroke
				(width 0.1524)
				(type default)
			)
			(layer "F.SilkS")
		)
		(fp_line
			(start 0.508 -1.525016)
			(end 1.3208 -1.525016)
			(stroke
				(width 0.1524)
				(type default)
			)
			(layer "F.SilkS")
		)
		(fp_line
			(start 1.3208 -1.525016)
			(end 1.3208 1.525016)
			(stroke
				(width 0.1524)
				(type default)
			)
			(layer "F.SilkS")
		)
		(fp_line
			(start 1.3208 1.525016)
			(end -1.3208 1.525016)
			(stroke
				(width 0.1524)
				(type default)
			)
			(layer "F.SilkS")
		)
		(fp_poly
			(pts
				(xy -2.877566 -1.364996) (xy -3.685794 -1.634236) (xy -3.14706 -2.173224)
			)
			(stroke
				(width 0)
				(type default)
			)
			(fill yes)
			(layer "F.SilkS")
		)
		(fp_line
			(start -3.037078 -1.20777)
			(end -1.524 -1.20777)
			(stroke
				(width 0.1)
				(type default)
			)
			(layer "F.Fab")
		)
		(fp_line
			(start -3.037078 1.203706)
			(end -3.037078 -1.20777)
			(stroke
				(width 0.1)
				(type default)
			)
			(layer "F.Fab")
		)
		(fp_line
			(start -1.5494 1.203706)
			(end -3.037078 1.203706)
			(stroke
				(width 0.1)
				(type default)
			)
			(layer "F.Fab")
		)
		(fp_line
			(start -1.5494 1.5494)
			(end -1.5494 1.203706)
			(stroke
				(width 0.1)
				(type default)
			)
			(layer "F.Fab")
		)
		(fp_line
			(start -1.524 -1.524)
			(end 1.524 -1.524)
			(stroke
				(width 0.1)
				(type default)
			)
			(layer "F.Fab")
		)
		(fp_line
			(start -1.524 -1.20777)
			(end -1.524 -1.524)
			(stroke
				(width 0.1)
				(type default)
			)
			(layer "F.Fab")
		)
		(fp_line
			(start 1.524 -1.524)
			(end 1.524 -1.20777)
			(stroke
				(width 0.1)
				(type default)
			)
			(layer "F.Fab")
		)
		(fp_line
			(start 1.524 -1.20777)
			(end 3.0353 -1.20777)
			(stroke
				(width 0.1)
				(type default)
			)
			(layer "F.Fab")
		)
		(fp_line
			(start 1.524 1.208786)
			(end 1.524 1.5494)
			(stroke
				(width 0.1)
				(type default)
			)
			(layer "F.Fab")
		)
		(fp_line
			(start 1.524 1.5494)
			(end -1.5494 1.5494)
			(stroke
				(width 0.1)
				(type default)
			)
			(layer "F.Fab")
		)
		(fp_line
			(start 3.0353 -1.20777)
			(end 3.0353 1.208786)
			(stroke
				(width 0.1)
				(type default)
			)
			(layer "F.Fab")
		)
		(fp_line
			(start 3.0353 1.208786)
			(end 1.524 1.208786)
			(stroke
				(width 0.1)
				(type default)
			)
			(layer "F.Fab")
		)
		(fp_poly
			(pts
				(xy -3.175 -1.016) (xy -3.937 -0.635) (xy -3.937 -1.397)
			)
			(stroke
				(width 0)
				(type default)
			)
			(fill yes)
			(layer "F.Fab")
		)
		(pad "1" smd rect
			(at -2.234946 -0.975106 270)
			(size 0.3556 1.4986)
			(layers "F.Cu" "F.Mask" "F.Paste")
			(net "P1V2_AUX")
		)
		(pad "2" smd rect
			(at -2.234946 -0.32512 270)
			(size 0.3556 1.4986)
			(layers "F.Cu" "F.Mask" "F.Paste")
			(net "SMB_NIC5_R_SDA")
		)
		(pad "3" smd rect
			(at -2.234946 0.32512 270)
			(size 0.3556 1.4986)
			(layers "F.Cu" "F.Mask" "F.Paste")
			(net "SMB_NIC5_R_SCL")
		)
		(pad "4" smd rect
			(at -2.234946 0.975106 270)
			(size 0.3556 1.4986)
			(layers "F.Cu" "F.Mask" "F.Paste")
			(net "GND")
		)
		(pad "5" smd rect
			(at 2.234946 0.975106 270)
			(size 0.3556 1.4986)
			(layers "F.Cu" "F.Mask" "F.Paste")
			(net "SMB_NIC5_LS_EN")
		)
		(pad "6" smd rect
			(at 2.234946 0.32512 270)
			(size 0.3556 1.4986)
			(layers "F.Cu" "F.Mask" "F.Paste")
			(net "SMB_NIC5_LS_R_SCL")
		)
		(pad "7" smd rect
			(at 2.234946 -0.32512 270)
			(size 0.3556 1.4986)
			(layers "F.Cu" "F.Mask" "F.Paste")
			(net "SMB_NIC5_LS_R_SDA")
		)
		(pad "8" smd rect
			(at 2.234946 -0.975106 270)
			(size 0.3556 1.4986)
			(layers "F.Cu" "F.Mask" "F.Paste")
			(net "P3V3_NIC5")
		)
	)
	(footprint ""
		(layer "F.Cu")
		(at 98.487484 -25.342342 -90)
		(property "Reference" "R420"
			(at 0 0 270)
			(layer "F.SilkS")
			(hide yes)
			(effects
				(font
					(size 1.27 1.27)
				)
			)
		)
		(property "Value" ""
			(at 0 0 270)
			(layer "F.Fab")
			(effects
				(font
					(size 1.27 1.27)
				)
			)
		)
		(duplicate_pad_numbers_are_jumpers no)
		(fp_line
			(start -0.7874 0.4064)
			(end -0.7874 -0.4064)
			(stroke
				(width 0.1524)
				(type default)
			)
			(layer "F.SilkS")
		)
		(fp_line
			(start 0.7874 0.4064)
			(end -0.7874 0.4064)
			(stroke
				(width 0.1524)
				(type default)
			)
			(layer "F.SilkS")
		)
		(fp_line
			(start -0.7874 -0.4064)
			(end 0.7874 -0.4064)
			(stroke
				(width 0.1524)
				(type default)
			)
			(layer "F.SilkS")
		)
		(fp_line
			(start 0.7874 -0.4064)
			(end 0.7874 0.4064)
			(stroke
				(width 0.1524)
				(type default)
			)
			(layer "F.SilkS")
		)
		(fp_line
			(start -0.67945 0.3048)
			(end -0.67945 -0.305054)
			(stroke
				(width 0.1)
				(type default)
			)
			(layer "F.Fab")
		)
		(fp_line
			(start -0.12065 0.3048)
			(end -0.67945 0.3048)
			(stroke
				(width 0.1)
				(type default)
			)
			(layer "F.Fab")
		)
		(fp_line
			(start 0.120396 0.3048)
			(end 0.120396 0.2794)
			(stroke
				(width 0.1)
				(type default)
			)
			(layer "F.Fab")
		)
		(fp_line
			(start 0.67945 0.3048)
			(end 0.120396 0.3048)
			(stroke
				(width 0.1)
				(type default)
			)
			(layer "F.Fab")
		)
		(fp_line
			(start -0.12065 0.2794)
			(end -0.12065 0.3048)
			(stroke
				(width 0.1)
				(type default)
			)
			(layer "F.Fab")
		)
		(fp_line
			(start 0.120396 0.2794)
			(end -0.12065 0.2794)
			(stroke
				(width 0.1)
				(type default)
			)
			(layer "F.Fab")
		)
		(fp_line
			(start -0.12065 -0.2794)
			(end 0.12065 -0.2794)
			(stroke
				(width 0.1)
				(type default)
			)
			(layer "F.Fab")
		)
		(fp_line
			(start 0.12065 -0.2794)
			(end 0.12065 -0.3048)
			(stroke
				(width 0.1)
				(type default)
			)
			(layer "F.Fab")
		)
		(fp_line
			(start 0.12065 -0.3048)
			(end 0.67945 -0.3048)
			(stroke
				(width 0.1)
				(type default)
			)
			(layer "F.Fab")
		)
		(fp_line
			(start 0.67945 -0.3048)
			(end 0.67945 0.3048)
			(stroke
				(width 0.1)
				(type default)
			)
			(layer "F.Fab")
		)
		(fp_line
			(start -0.67945 -0.305054)
			(end -0.12065 -0.305054)
			(stroke
				(width 0.1)
				(type default)
			)
			(layer "F.Fab")
		)
		(fp_line
			(start -0.12065 -0.305054)
			(end -0.12065 -0.2794)
			(stroke
				(width 0.1)
				(type default)
			)
			(layer "F.Fab")
		)
		(pad "1" smd circle
			(at -0.40005 0 270)
			(size 0 0)
			(layers "F.Cu" "F.Mask" "F.Paste")
			(net "GND")
		)
		(pad "2" smd circle
			(at 0.40005 0 270)
			(size 0 0)
			(layers "F.Cu" "F.Mask" "F.Paste")
			(net "DUALPORT_N_SSD3")
		)
	)
)
